(kicad_pcb
	(version 20260206)
	(generator "pcbnew")
	(generator_version "10.0")
	(general
		(thickness 1.6)
		(legacy_teardrops no)
	)
	(paper "A4")
	(title_block
		(title "pdpb — Lightning_PDPB_BRD.brd")
		(comment 1 "Lightning (Wiwynn / Facebook NVMe JBOF) / footprints 572-578 of 1140")
	)
	(layers
		(0 "F.Cu" signal "TOP")
		(4 "In1.Cu" signal "L2GND")
		(6 "In2.Cu" signal "L3")
		(8 "In3.Cu" signal "L4VCC")
		(10 "In4.Cu" signal "L5VCC")
		(12 "In5.Cu" signal "L6")
		(14 "In6.Cu" signal "L7GND")
		(2 "B.Cu" signal "BOTTOM")
		(9 "F.Adhes" user "F.Adhesive")
		(11 "B.Adhes" user "B.Adhesive")
		(13 "F.Paste" user "Package Geometry/Pastemask Top")
		(15 "B.Paste" user "Package Geometry/Pastemask Bottom")
		(5 "F.SilkS" user "Ref Des/Silkscreen Top")
		(7 "B.SilkS" user "Ref Des/Silkscreen Bottom")
		(1 "F.Mask" user "Board Geometry/Soldermask Top")
		(3 "B.Mask" user "Board Geometry/Soldermask Bottom")
		(17 "Dwgs.User" user "User.Drawings")
		(19 "Cmts.User" user "User.Comments")
		(21 "Eco1.User" user "User.Eco1")
		(23 "Eco2.User" user "User.Eco2")
		(25 "Edge.Cuts" user "Board Geometry/Outline")
		(27 "Margin" user)
		(31 "F.CrtYd" user "Package Geometry/Place Bound Top")
		(29 "B.CrtYd" user "Package Geometry/Place Bound Bottom")
		(35 "F.Fab" user "Ref Des/Assembly Top")
		(33 "B.Fab" user "Ref Des/Assembly Bottom")
	)
	(footprint ""
		(layer "F.Cu")
		(at 49.149 -145.669 -90)
		(property "Reference" "R9428"
			(at 0 0 270)
			(layer "F.SilkS")
			(hide yes)
			(effects
				(font
					(size 1.27 1.27)
				)
			)
		)
		(property "Value" "330R2F-GP"
			(at 0.064008 -3.993896 270)
			(unlocked yes)
			(layer "F.Fab")
			(hide yes)
			(effects
				(font
					(size 1.016 1.016)
					(thickness 0.1524)
				)
			)
		)
		(property "Device Type" "R402H16"
			(at 0.064008 -5.517896 270)
			(unlocked yes)
			(layer "F.Fab")
			(hide yes)
			(effects
				(font
					(size 1.016 1.016)
					(thickness 0.1524)
				)
			)
		)
		(duplicate_pad_numbers_are_jumpers no)
		(fp_line
			(start -0.508 -0.9398)
			(end -0.508 0.9398)
			(stroke
				(width 0.1524)
				(type default)
			)
			(layer "F.SilkS")
		)
		(fp_line
			(start 0.508 -0.9398)
			(end -0.508 -0.9398)
			(stroke
				(width 0.1524)
				(type default)
			)
			(layer "F.SilkS")
		)
		(fp_rect
			(start -0.508 0.9398)
			(end 0.508 -0.9398)
			(stroke
				(width 0)
				(type default)
			)
			(fill no)
			(layer "F.CrtYd")
		)
		(fp_rect
			(start -0.508 0.9398)
			(end 0.508 -0.9398)
			(stroke
				(width 0)
				(type default)
			)
			(fill no)
			(layer "F.Fab")
		)
		(pad "1" smd custom
			(at 0 -0.4445 270)
			(size 0.1397 0.1397)
			(layers "F.Cu" "F.Mask" "F.Paste")
			(net "P3V3")
			(options
				(clearance outline)
				(anchor circle)
			)
			(primitives
				(gr_poly
					(pts
						(arc
							(start -0.1778 -0.2794)
							(mid -0.249642 -0.249642)
							(end -0.2794 -0.1778)
						)
						(arc
							(start -0.2794 0.1778)
							(mid -0.249642 0.249642)
							(end -0.1778 0.2794)
						)
						(arc
							(start 0.1778 0.2794)
							(mid 0.249642 0.249642)
							(end 0.2794 0.1778)
						)
						(arc
							(start 0.2794 -0.1778)
							(mid 0.249642 -0.249642)
							(end 0.1778 -0.2794)
						)
					)
					(width 0)
					(fill yes)
				)
			)
		)
		(pad "2" smd custom
			(at 0 0.4445 270)
			(size 0.1397 0.1397)
			(layers "F.Cu" "F.Mask" "F.Paste")
			(net "DRV_ATTN_8")
			(options
				(clearance outline)
				(anchor circle)
			)
			(primitives
				(gr_poly
					(pts
						(arc
							(start -0.1778 -0.2794)
							(mid -0.249642 -0.249642)
							(end -0.2794 -0.1778)
						)
						(arc
							(start -0.2794 0.1778)
							(mid -0.249642 0.249642)
							(end -0.1778 0.2794)
						)
						(arc
							(start 0.1778 0.2794)
							(mid 0.249642 0.249642)
							(end 0.2794 0.1778)
						)
						(arc
							(start 0.2794 -0.1778)
							(mid 0.249642 -0.249642)
							(end 0.1778 -0.2794)
						)
					)
					(width 0)
					(fill yes)
				)
			)
		)
	)
	(footprint ""
		(layer "F.Cu")
		(at 87.757 -113.665 -90)
		(property "Reference" "C9373"
			(at 0 0 270)
			(layer "F.SilkS")
			(hide yes)
			(effects
				(font
					(size 1.27 1.27)
				)
			)
		)
		(property "Value" "SC1KP50V2KX-1GP"
			(at 1.1811 -2.7051 270)
			(unlocked yes)
			(layer "F.Fab")
			(hide yes)
			(effects
				(font
					(size 1.016 1.016)
					(thickness 0.1524)
				)
			)
		)
		(property "Device Type" "C402H22"
			(at 1.1811 -4.2291 270)
			(unlocked yes)
			(layer "F.Fab")
			(hide yes)
			(effects
				(font
					(size 1.016 1.016)
					(thickness 0.1524)
				)
			)
		)
		(duplicate_pad_numbers_are_jumpers no)
		(fp_rect
			(start -0.4318 0.9525)
			(end 0.4318 -0.9525)
			(stroke
				(width 0)
				(type default)
			)
			(fill no)
			(layer "F.CrtYd")
		)
		(fp_rect
			(start -0.4318 0.9525)
			(end 0.4318 -0.9525)
			(stroke
				(width 0)
				(type default)
			)
			(fill no)
			(layer "F.Fab")
		)
		(pad "1" smd custom
			(at 0 -0.4445 270)
			(size 0.1524 0.1524)
			(layers "F.Cu" "F.Mask" "F.Paste")
			(net "SSD13_CLK0_OE_R_N")
			(options
				(clearance outline)
				(anchor circle)
			)
			(primitives
				(gr_poly
					(pts
						(arc
							(start 0.3048 -0.2032)
							(mid 0.275042 -0.275042)
							(end 0.2032 -0.3048)
						)
						(arc
							(start -0.2032 -0.3048)
							(mid -0.275042 -0.275042)
							(end -0.3048 -0.2032)
						)
						(arc
							(start -0.3048 0.2032)
							(mid -0.275042 0.275042)
							(end -0.2032 0.3048)
						)
						(arc
							(start 0.2032 0.3048)
							(mid 0.275042 0.275042)
							(end 0.3048 0.2032)
						)
					)
					(width 0)
					(fill yes)
				)
			)
		)
		(pad "2" smd custom
			(at 0 0.4445 270)
			(size 0.1524 0.1524)
			(layers "F.Cu" "F.Mask" "F.Paste")
			(net "GND")
			(options
				(clearance outline)
				(anchor circle)
			)
			(primitives
				(gr_poly
					(pts
						(arc
							(start 0.3048 -0.2032)
							(mid 0.275042 -0.275042)
							(end 0.2032 -0.3048)
						)
						(arc
							(start -0.2032 -0.3048)
							(mid -0.275042 -0.275042)
							(end -0.3048 -0.2032)
						)
						(arc
							(start -0.3048 0.2032)
							(mid -0.275042 0.275042)
							(end -0.2032 0.3048)
						)
						(arc
							(start 0.2032 0.3048)
							(mid 0.275042 0.275042)
							(end 0.3048 0.2032)
						)
					)
					(width 0)
					(fill yes)
				)
			)
		)
	)
	(footprint ""
		(layer "F.Cu")
		(at 87.757 -443.865 -90)
		(property "Reference" "C9367"
			(at 0 0 270)
			(layer "F.SilkS")
			(hide yes)
			(effects
				(font
					(size 1.27 1.27)
				)
			)
		)
		(property "Value" "SC1KP50V2KX-1GP"
			(at 1.1811 -2.7051 270)
			(unlocked yes)
			(layer "F.Fab")
			(hide yes)
			(effects
				(font
					(size 1.016 1.016)
					(thickness 0.1524)
				)
			)
		)
		(property "Device Type" "C402H22"
			(at 1.1811 -4.2291 270)
			(unlocked yes)
			(layer "F.Fab")
			(hide yes)
			(effects
				(font
					(size 1.016 1.016)
					(thickness 0.1524)
				)
			)
		)
		(duplicate_pad_numbers_are_jumpers no)
		(fp_rect
			(start -0.4318 0.9525)
			(end 0.4318 -0.9525)
			(stroke
				(width 0)
				(type default)
			)
			(fill no)
			(layer "F.CrtYd")
		)
		(fp_rect
			(start -0.4318 0.9525)
			(end 0.4318 -0.9525)
			(stroke
				(width 0)
				(type default)
			)
			(fill no)
			(layer "F.Fab")
		)
		(pad "1" smd custom
			(at 0 -0.4445 270)
			(size 0.1524 0.1524)
			(layers "F.Cu" "F.Mask" "F.Paste")
			(net "SSD5_CLK0_OE_R_N")
			(options
				(clearance outline)
				(anchor circle)
			)
			(primitives
				(gr_poly
					(pts
						(arc
							(start 0.3048 -0.2032)
							(mid 0.275042 -0.275042)
							(end 0.2032 -0.3048)
						)
						(arc
							(start -0.2032 -0.3048)
							(mid -0.275042 -0.275042)
							(end -0.3048 -0.2032)
						)
						(arc
							(start -0.3048 0.2032)
							(mid -0.275042 0.275042)
							(end -0.2032 0.3048)
						)
						(arc
							(start 0.2032 0.3048)
							(mid 0.275042 0.275042)
							(end 0.3048 0.2032)
						)
					)
					(width 0)
					(fill yes)
				)
			)
		)
		(pad "2" smd custom
			(at 0 0.4445 270)
			(size 0.1524 0.1524)
			(layers "F.Cu" "F.Mask" "F.Paste")
			(net "GND")
			(options
				(clearance outline)
				(anchor circle)
			)
			(primitives
				(gr_poly
					(pts
						(arc
							(start 0.3048 -0.2032)
							(mid 0.275042 -0.275042)
							(end 0.2032 -0.3048)
						)
						(arc
							(start -0.2032 -0.3048)
							(mid -0.275042 -0.275042)
							(end -0.3048 -0.2032)
						)
						(arc
							(start -0.3048 0.2032)
							(mid -0.275042 0.275042)
							(end -0.2032 0.3048)
						)
						(arc
							(start 0.2032 0.3048)
							(mid 0.275042 0.275042)
							(end 0.3048 0.2032)
						)
					)
					(width 0)
					(fill yes)
				)
			)
		)
	)
	(footprint ""
		(layer "F.Cu")
		(at 88.138 -318.643)
		(property "Reference" "R9611"
			(at 0 0 0)
			(layer "F.SilkS")
			(hide yes)
			(effects
				(font
					(size 1.27 1.27)
				)
			)
		)
		(property "Value" "10R2F-L-GP"
			(at 0.064008 -3.993896 0)
			(unlocked yes)
			(layer "F.Fab")
			(hide yes)
			(effects
				(font
					(size 1.016 1.016)
					(thickness 0.1524)
				)
			)
		)
		(property "Device Type" "R402H14"
			(at 0.064008 -5.517896 0)
			(unlocked yes)
			(layer "F.Fab")
			(hide yes)
			(effects
				(font
					(size 1.016 1.016)
					(thickness 0.1524)
				)
			)
		)
		(duplicate_pad_numbers_are_jumpers no)
		(fp_line
			(start -0.508 -0.9398)
			(end -0.508 0.9398)
			(stroke
				(width 0.1524)
				(type default)
			)
			(layer "F.SilkS")
		)
		(fp_line
			(start 0.508 -0.9398)
			(end -0.508 -0.9398)
			(stroke
				(width 0.1524)
				(type default)
			)
			(layer "F.SilkS")
		)
		(fp_rect
			(start -0.508 0.9398)
			(end 0.508 -0.9398)
			(stroke
				(width 0)
				(type default)
			)
			(fill no)
			(layer "F.CrtYd")
		)
		(fp_rect
			(start -0.508 0.9398)
			(end 0.508 -0.9398)
			(stroke
				(width 0)
				(type default)
			)
			(fill no)
			(layer "F.Fab")
		)
		(pad "1" smd custom
			(at 0 -0.4445)
			(size 0.1397 0.1397)
			(layers "F.Cu" "F.Mask" "F.Paste")
			(net "SSD11_CLK0_OE_N")
			(options
				(clearance outline)
				(anchor circle)
			)
			(primitives
				(gr_poly
					(pts
						(arc
							(start -0.1778 -0.2794)
							(mid -0.249642 -0.249642)
							(end -0.2794 -0.1778)
						)
						(arc
							(start -0.2794 0.1778)
							(mid -0.249642 0.249642)
							(end -0.1778 0.2794)
						)
						(arc
							(start 0.1778 0.2794)
							(mid 0.249642 0.249642)
							(end 0.2794 0.1778)
						)
						(arc
							(start 0.2794 -0.1778)
							(mid 0.249642 -0.249642)
							(end 0.1778 -0.2794)
						)
					)
					(width 0)
					(fill yes)
				)
			)
		)
		(pad "2" smd custom
			(at 0 0.4445)
			(size 0.1397 0.1397)
			(layers "F.Cu" "F.Mask" "F.Paste")
			(net "SSD11_CLK0_OE_R_N")
			(options
				(clearance outline)
				(anchor circle)
			)
			(primitives
				(gr_poly
					(pts
						(arc
							(start -0.1778 -0.2794)
							(mid -0.249642 -0.249642)
							(end -0.2794 -0.1778)
						)
						(arc
							(start -0.2794 0.1778)
							(mid -0.249642 0.249642)
							(end -0.1778 0.2794)
						)
						(arc
							(start 0.1778 0.2794)
							(mid 0.249642 0.249642)
							(end 0.2794 0.1778)
						)
						(arc
							(start 0.2794 -0.1778)
							(mid 0.249642 -0.249642)
							(end 0.1778 -0.2794)
						)
					)
					(width 0)
					(fill yes)
				)
			)
		)
	)
	(footprint ""
		(layer "F.Cu")
		(at 86.614 -306.324 180)
		(property "Reference" "C8911"
			(at 0 0 180)
			(layer "F.SilkS")
			(hide yes)
			(effects
				(font
					(size 1.27 1.27)
				)
			)
		)
		(property "Value" "SC1U10V2KX-7-GP"
			(at 1.1811 -2.7051 180)
			(unlocked yes)
			(layer "F.Fab")
			(hide yes)
			(effects
				(font
					(size 1.016 1.016)
					(thickness 0.1524)
				)
			)
		)
		(property "Device Type" "C402H22"
			(at 1.1811 -4.2291 180)
			(unlocked yes)
			(layer "F.Fab")
			(hide yes)
			(effects
				(font
					(size 1.016 1.016)
					(thickness 0.1524)
				)
			)
		)
		(duplicate_pad_numbers_are_jumpers no)
		(fp_rect
			(start -0.4318 0.9525)
			(end 0.4318 -0.9525)
			(stroke
				(width 0)
				(type default)
			)
			(fill no)
			(layer "F.CrtYd")
		)
		(fp_rect
			(start -0.4318 0.9525)
			(end 0.4318 -0.9525)
			(stroke
				(width 0)
				(type default)
			)
			(fill no)
			(layer "F.Fab")
		)
		(pad "1" smd custom
			(at 0 -0.4445 180)
			(size 0.1524 0.1524)
			(layers "F.Cu" "F.Mask" "F.Paste")
			(net "VDDR_2")
			(options
				(clearance outline)
				(anchor circle)
			)
			(primitives
				(gr_poly
					(pts
						(arc
							(start 0.3048 -0.2032)
							(mid 0.275042 -0.275042)
							(end 0.2032 -0.3048)
						)
						(arc
							(start -0.2032 -0.3048)
							(mid -0.275042 -0.275042)
							(end -0.3048 -0.2032)
						)
						(arc
							(start -0.3048 0.2032)
							(mid -0.275042 0.275042)
							(end -0.2032 0.3048)
						)
						(arc
							(start 0.2032 0.3048)
							(mid 0.275042 0.275042)
							(end 0.3048 0.2032)
						)
					)
					(width 0)
					(fill yes)
				)
			)
		)
		(pad "2" smd custom
			(at 0 0.4445 180)
			(size 0.1524 0.1524)
			(layers "F.Cu" "F.Mask" "F.Paste")
			(net "GND")
			(options
				(clearance outline)
				(anchor circle)
			)
			(primitives
				(gr_poly
					(pts
						(arc
							(start 0.3048 -0.2032)
							(mid 0.275042 -0.275042)
							(end 0.2032 -0.3048)
						)
						(arc
							(start -0.2032 -0.3048)
							(mid -0.275042 -0.275042)
							(end -0.3048 -0.2032)
						)
						(arc
							(start -0.3048 0.2032)
							(mid -0.275042 0.275042)
							(end -0.2032 0.3048)
						)
						(arc
							(start 0.2032 0.3048)
							(mid 0.275042 0.275042)
							(end 0.3048 0.2032)
						)
					)
					(width 0)
					(fill yes)
				)
			)
		)
	)
	(footprint ""
		(layer "F.Cu")
		(at 22.14245 -95.95485 90)
		(property "Reference" "R9839"
			(at 0 0 90)
			(layer "F.SilkS")
			(hide yes)
			(effects
				(font
					(size 1.27 1.27)
				)
			)
		)
		(property "Value" "1KR2J-1-GP"
			(at 0.064008 -3.993896 90)
			(unlocked yes)
			(layer "F.Fab")
			(hide yes)
			(effects
				(font
					(size 1.016 1.016)
					(thickness 0.1524)
				)
			)
		)
		(property "Device Type" "R402H16"
			(at 0.064008 -5.517896 90)
			(unlocked yes)
			(layer "F.Fab")
			(hide yes)
			(effects
				(font
					(size 1.016 1.016)
					(thickness 0.1524)
				)
			)
		)
		(duplicate_pad_numbers_are_jumpers no)
		(fp_line
			(start 0.508 -0.9398)
			(end -0.508 -0.9398)
			(stroke
				(width 0.1524)
				(type default)
			)
			(layer "F.SilkS")
		)
		(fp_line
			(start -0.508 -0.9398)
			(end -0.508 0.9398)
			(stroke
				(width 0.1524)
				(type default)
			)
			(layer "F.SilkS")
		)
		(fp_rect
			(start -0.508 0.9398)
			(end 0.508 -0.9398)
			(stroke
				(width 0)
				(type default)
			)
			(fill no)
			(layer "F.CrtYd")
		)
		(fp_rect
			(start -0.508 0.9398)
			(end 0.508 -0.9398)
			(stroke
				(width 0)
				(type default)
			)
			(fill no)
			(layer "F.Fab")
		)
		(pad "1" smd custom
			(at 0 -0.4445 90)
			(size 0.1397 0.1397)
			(layers "F.Cu" "F.Mask" "F.Paste")
			(net "SSD9_PWREN")
			(options
				(clearance outline)
				(anchor circle)
			)
			(primitives
				(gr_poly
					(pts
						(arc
							(start -0.1778 -0.2794)
							(mid -0.249642 -0.249642)
							(end -0.2794 -0.1778)
						)
						(arc
							(start -0.2794 0.1778)
							(mid -0.249642 0.249642)
							(end -0.1778 0.2794)
						)
						(arc
							(start 0.1778 0.2794)
							(mid 0.249642 0.249642)
							(end 0.2794 0.1778)
						)
						(arc
							(start 0.2794 -0.1778)
							(mid 0.249642 -0.249642)
							(end 0.1778 -0.2794)
						)
					)
					(width 0)
					(fill yes)
				)
			)
		)
		(pad "2" smd custom
			(at 0 0.4445 90)
			(size 0.1397 0.1397)
			(layers "F.Cu" "F.Mask" "F.Paste")
			(net "SSD9_PWREN_R")
			(options
				(clearance outline)
				(anchor circle)
			)
			(primitives
				(gr_poly
					(pts
						(arc
							(start -0.1778 -0.2794)
							(mid -0.249642 -0.249642)
							(end -0.2794 -0.1778)
						)
						(arc
							(start -0.2794 0.1778)
							(mid -0.249642 0.249642)
							(end -0.1778 0.2794)
						)
						(arc
							(start 0.1778 0.2794)
							(mid 0.249642 0.249642)
							(end 0.2794 0.1778)
						)
						(arc
							(start 0.2794 -0.1778)
							(mid 0.249642 -0.249642)
							(end 0.1778 -0.2794)
						)
					)
					(width 0)
					(fill yes)
				)
			)
		)
	)
	(footprint ""
		(layer "F.Cu")
		(at 25.71115 -101.86035 90)
		(property "Reference" "R9864"
			(at 0 0 90)
			(layer "F.SilkS")
			(hide yes)
			(effects
				(font
					(size 1.27 1.27)
				)
			)
		)
		(property "Value" "2K2R5F-GP"
			(at 0 -8.9535 90)
			(unlocked yes)
			(layer "F.Fab")
			(hide yes)
			(effects
				(font
					(size 1.27 1.016)
					(thickness 0.1524)
				)
			)
		)
		(property "Device Type" "R805H24"
			(at 0 -10.6299 90)
			(unlocked yes)
			(layer "F.Fab")
			(hide yes)
			(effects
				(font
					(size 1.27 1.016)
					(thickness 0.1524)
				)
			)
		)
		(duplicate_pad_numbers_are_jumpers no)
		(fp_line
			(start 0.889 -1.7018)
			(end -0.889 -1.7018)
			(stroke
				(width 0.1524)
				(type default)
			)
			(layer "F.SilkS")
		)
		(fp_line
			(start 0.889 -1.7018)
			(end 0.889 -0.381)
			(stroke
				(width 0.1524)
				(type default)
			)
			(layer "F.SilkS")
		)
		(fp_line
			(start -0.889 -1.7018)
			(end -0.889 0.2794)
			(stroke
				(width 0.1524)
				(type default)
			)
			(layer "F.SilkS")
		)
		(fp_line
			(start -0.889 0.0762)
			(end -0.889 1.7018)
			(stroke
				(width 0.1524)
				(type default)
			)
			(layer "F.SilkS")
		)
		(fp_line
			(start 0.889 1.7018)
			(end 0.889 -0.508)
			(stroke
				(width 0.1524)
				(type default)
			)
			(layer "F.SilkS")
		)
		(fp_line
			(start -0.889 1.7018)
			(end 0.889 1.7018)
			(stroke
				(width 0.1524)
				(type default)
			)
			(layer "F.SilkS")
		)
		(fp_poly
			(pts
				(xy 0.9652 -1.778) (xy 0.9652 1.778) (xy -0.9652 1.778) (xy -0.9652 -1.778)
			)
			(stroke
				(width 0)
				(type default)
			)
			(fill no)
			(layer "F.CrtYd")
		)
		(fp_rect
			(start -0.9652 1.778)
			(end 0.9652 -1.778)
			(stroke
				(width 0)
				(type default)
			)
			(fill no)
			(layer "F.Fab")
		)
		(pad "1" smd rect
			(at 0 -0.9652 90)
			(size 1.397 1.143)
			(layers "F.Cu" "F.Mask" "F.Paste")
			(net "P12V_SSD13")
		)
		(pad "2" smd rect
			(at 0 0.9652 90)
			(size 1.397 1.143)
			(layers "F.Cu" "F.Mask" "F.Paste")
			(net "P12V_MOST13_GATE_D")
		)
	)
)
